(kicad_pcb
	(version 20260206)
	(generator "pcbnew")
	(generator_version "10.0")
	(general
		(thickness 1.6)
		(legacy_teardrops no)
	)
	(paper "A4")
	(title_block
		(title "01162023_DA0F0TEBIF0_F0T_Expander_BD_F_brd_V02_OCP.brd")
		(comment 1 "Grand Teton / footprints 1622-1628 of 9728")
	)
	(layers
		(0 "F.Cu" signal "TOP")
		(4 "In1.Cu" signal "GND")
		(6 "In2.Cu" signal "VCC")
		(8 "In3.Cu" signal "VCC1")
		(10 "In4.Cu" signal "GND1")
		(12 "In5.Cu" signal "IN1")
		(14 "In6.Cu" signal "GND2")
		(16 "In7.Cu" signal "IN2")
		(18 "In8.Cu" signal "GND3")
		(20 "In9.Cu" signal "IN3")
		(22 "In10.Cu" signal "GND4")
		(24 "In11.Cu" signal "IN4")
		(26 "In12.Cu" signal "GND5")
		(28 "In13.Cu" signal "IN5")
		(30 "In14.Cu" signal "GND6")
		(32 "In15.Cu" signal "IN6")
		(34 "In16.Cu" signal "GND7")
		(2 "B.Cu" signal "BOTTOM")
		(9 "F.Adhes" user "F.Adhesive")
		(11 "B.Adhes" user "B.Adhesive")
		(13 "F.Paste" user "Package Geometry/Pastemask Top")
		(15 "B.Paste" user "Package Geometry/Pastemask Bottom")
		(5 "F.SilkS" user "Ref Des/Silkscreen Top")
		(7 "B.SilkS" user "Ref Des/Silkscreen Bottom")
		(1 "F.Mask" user "Board Geometry/Soldermask Top")
		(3 "B.Mask" user "Board Geometry/Soldermask Bottom")
		(17 "Dwgs.User" user "User.Drawings")
		(19 "Cmts.User" user "User.Comments")
		(21 "Eco1.User" user "User.Eco1")
		(23 "Eco2.User" user "User.Eco2")
		(25 "Edge.Cuts" user "Board Geometry/Outline")
		(27 "Margin" user)
		(31 "F.CrtYd" user "Package Geometry/Place Bound Top")
		(29 "B.CrtYd" user "Package Geometry/Place Bound Bottom")
		(35 "F.Fab" user "Ref Des/Assembly Top")
		(33 "B.Fab" user "Ref Des/Assembly Bottom")
	)
	(footprint ""
		(layer "F.Cu")
		(at 361.188 -191.262 180)
		(property "Reference" "R4654"
			(at 0 0 180)
			(layer "F.SilkS")
			(hide yes)
			(effects
				(font
					(size 1.27 1.27)
				)
			)
		)
		(property "Value" ""
			(at 0 0 180)
			(layer "F.Fab")
			(effects
				(font
					(size 1.27 1.27)
				)
			)
		)
		(duplicate_pad_numbers_are_jumpers no)
		(fp_line
			(start 0.7874 0.4064)
			(end -0.7874 0.4064)
			(stroke
				(width 0.1524)
				(type default)
			)
			(layer "F.SilkS")
		)
		(fp_line
			(start 0.7874 -0.4064)
			(end 0.7874 0.4064)
			(stroke
				(width 0.1524)
				(type default)
			)
			(layer "F.SilkS")
		)
		(fp_line
			(start -0.7874 0.4064)
			(end -0.7874 -0.4064)
			(stroke
				(width 0.1524)
				(type default)
			)
			(layer "F.SilkS")
		)
		(fp_line
			(start -0.7874 -0.4064)
			(end 0.7874 -0.4064)
			(stroke
				(width 0.1524)
				(type default)
			)
			(layer "F.SilkS")
		)
		(fp_line
			(start 0.67945 0.3048)
			(end 0.120396 0.3048)
			(stroke
				(width 0.1)
				(type default)
			)
			(layer "F.Fab")
		)
		(fp_line
			(start 0.67945 -0.3048)
			(end 0.67945 0.3048)
			(stroke
				(width 0.1)
				(type default)
			)
			(layer "F.Fab")
		)
		(fp_line
			(start 0.12065 -0.2794)
			(end 0.12065 -0.3048)
			(stroke
				(width 0.1)
				(type default)
			)
			(layer "F.Fab")
		)
		(fp_line
			(start 0.12065 -0.3048)
			(end 0.67945 -0.3048)
			(stroke
				(width 0.1)
				(type default)
			)
			(layer "F.Fab")
		)
		(fp_line
			(start 0.120396 0.3048)
			(end 0.120396 0.2794)
			(stroke
				(width 0.1)
				(type default)
			)
			(layer "F.Fab")
		)
		(fp_line
			(start 0.120396 0.2794)
			(end -0.12065 0.2794)
			(stroke
				(width 0.1)
				(type default)
			)
			(layer "F.Fab")
		)
		(fp_line
			(start -0.12065 0.3048)
			(end -0.67945 0.3048)
			(stroke
				(width 0.1)
				(type default)
			)
			(layer "F.Fab")
		)
		(fp_line
			(start -0.12065 0.2794)
			(end -0.12065 0.3048)
			(stroke
				(width 0.1)
				(type default)
			)
			(layer "F.Fab")
		)
		(fp_line
			(start -0.12065 -0.2794)
			(end 0.12065 -0.2794)
			(stroke
				(width 0.1)
				(type default)
			)
			(layer "F.Fab")
		)
		(fp_line
			(start -0.12065 -0.305054)
			(end -0.12065 -0.2794)
			(stroke
				(width 0.1)
				(type default)
			)
			(layer "F.Fab")
		)
		(fp_line
			(start -0.67945 0.3048)
			(end -0.67945 -0.305054)
			(stroke
				(width 0.1)
				(type default)
			)
			(layer "F.Fab")
		)
		(fp_line
			(start -0.67945 -0.305054)
			(end -0.12065 -0.305054)
			(stroke
				(width 0.1)
				(type default)
			)
			(layer "F.Fab")
		)
		(pad "1" smd circle
			(at -0.40005 0 180)
			(size 0 0)
			(layers "F.Cu" "F.Mask" "F.Paste")
			(net "GND")
		)
		(pad "2" smd circle
			(at 0.40005 0 180)
			(size 0 0)
			(layers "F.Cu" "F.Mask" "F.Paste")
			(net "PCA9555_1_PEX0_A2")
		)
	)
	(footprint ""
		(layer "F.Cu")
		(at 278.112982 -356.244906 90)
		(property "Reference" "C604"
			(at 0 0 90)
			(layer "F.SilkS")
			(hide yes)
			(effects
				(font
					(size 1.27 1.27)
				)
			)
		)
		(property "Value" ""
			(at 0 0 90)
			(layer "F.Fab")
			(effects
				(font
					(size 1.27 1.27)
				)
			)
		)
		(duplicate_pad_numbers_are_jumpers no)
		(fp_line
			(start 0.299974 -0.150114)
			(end 0.299974 0.150114)
			(stroke
				(width 0.1)
				(type default)
			)
			(layer "F.Fab")
		)
		(fp_line
			(start -0.299974 -0.150114)
			(end 0.299974 -0.150114)
			(stroke
				(width 0.1)
				(type default)
			)
			(layer "F.Fab")
		)
		(fp_line
			(start 0.299974 0.150114)
			(end -0.299974 0.150114)
			(stroke
				(width 0.1)
				(type default)
			)
			(layer "F.Fab")
		)
		(fp_line
			(start -0.299974 0.150114)
			(end -0.299974 -0.150114)
			(stroke
				(width 0.1)
				(type default)
			)
			(layer "F.Fab")
		)
		(pad "1" smd rect
			(at -0.2667 0 90)
			(size 0.3048 0.381)
			(layers "F.Cu" "F.Mask" "F.Paste")
			(net "P5E_PEX2_STN7_TX_DN<117>")
		)
		(pad "2" smd rect
			(at 0.2667 0 90)
			(size 0.3048 0.381)
			(layers "F.Cu" "F.Mask" "F.Paste")
			(net "P5E_PEX2_STN7_TX_C_DN<117>")
		)
	)
	(footprint ""
		(layer "F.Cu")
		(at 254.339598 -213.934294)
		(property "Reference" "U342"
			(at -1.152398 2.810764 0)
			(unlocked yes)
			(layer "F.SilkS")
			(effects
				(font
					(size 0.7874 0.5842)
					(thickness 0.1524)
				)
				(justify left)
			)
		)
		(property "Value" ""
			(at 0 0 0)
			(layer "F.Fab")
			(effects
				(font
					(size 1.27 1.27)
				)
			)
		)
		(duplicate_pad_numbers_are_jumpers no)
		(fp_line
			(start -1.525016 -1.525016)
			(end -1.525016 -1.3208)
			(stroke
				(width 0.1524)
				(type default)
			)
			(layer "F.SilkS")
		)
		(fp_line
			(start -1.525016 1.3208)
			(end -1.525016 1.525016)
			(stroke
				(width 0.1524)
				(type default)
			)
			(layer "F.SilkS")
		)
		(fp_line
			(start -1.525016 1.525016)
			(end -0.889 1.525016)
			(stroke
				(width 0.1524)
				(type default)
			)
			(layer "F.SilkS")
		)
		(fp_line
			(start -0.8636 -1.525016)
			(end -1.525016 -1.525016)
			(stroke
				(width 0.1524)
				(type default)
			)
			(layer "F.SilkS")
		)
		(fp_line
			(start 0.9906 1.525016)
			(end 1.525016 1.525016)
			(stroke
				(width 0.1524)
				(type default)
			)
			(layer "F.SilkS")
		)
		(fp_line
			(start 1.525016 -1.525016)
			(end -1.525016 -1.525016)
			(stroke
				(width 0.1524)
				(type default)
			)
			(layer "F.SilkS")
		)
		(fp_line
			(start 1.525016 -1.525016)
			(end 0.9398 -1.525016)
			(stroke
				(width 0.1524)
				(type default)
			)
			(layer "F.SilkS")
		)
		(fp_line
			(start 1.525016 -1.3208)
			(end 1.525016 -1.525016)
			(stroke
				(width 0.1524)
				(type default)
			)
			(layer "F.SilkS")
		)
		(fp_line
			(start 1.525016 1.525016)
			(end -1.525016 1.525016)
			(stroke
				(width 0.1524)
				(type default)
			)
			(layer "F.SilkS")
		)
		(fp_line
			(start 1.525016 1.525016)
			(end 1.525016 1.3208)
			(stroke
				(width 0.1524)
				(type default)
			)
			(layer "F.SilkS")
		)
		(fp_poly
			(pts
				(xy -1.522222 -1.738122) (xy -1.222248 -2.638298) (xy -1.822196 -2.638298)
			)
			(stroke
				(width 0)
				(type default)
			)
			(fill yes)
			(layer "F.SilkS")
		)
		(fp_line
			(start -1.525016 -1.525016)
			(end 1.525016 -1.525016)
			(stroke
				(width 0.1)
				(type default)
			)
			(layer "F.Fab")
		)
		(fp_line
			(start -1.525016 1.525016)
			(end -1.525016 -1.525016)
			(stroke
				(width 0.1)
				(type default)
			)
			(layer "F.Fab")
		)
		(fp_line
			(start 1.525016 -1.525016)
			(end 1.525016 1.525016)
			(stroke
				(width 0.1)
				(type default)
			)
			(layer "F.Fab")
		)
		(fp_line
			(start 1.525016 1.525016)
			(end -1.525016 1.525016)
			(stroke
				(width 0.1)
				(type default)
			)
			(layer "F.Fab")
		)
		(fp_poly
			(pts
				(xy -2.0701 -0.999998) (xy -2.977896 -1.302512) (xy -2.977896 -0.697484)
			)
			(stroke
				(width 0)
				(type default)
			)
			(fill yes)
			(layer "F.Fab")
		)
		(pad "1" smd rect
			(at -1.550162 -0.999998 270)
			(size 0.2794 0.9144)
			(layers "F.Cu" "F.Mask" "F.Paste")
			(net "P1V2_AUX")
		)
		(pad "2" smd rect
			(at -1.550162 -0.500126 270)
			(size 0.2794 0.9144)
			(layers "F.Cu" "F.Mask" "F.Paste")
			(net "P1V2_AUX")
		)
		(pad "3" smd rect
			(at -1.550162 0 270)
			(size 0.2794 0.9144)
			(layers "F.Cu" "F.Mask" "F.Paste")
			(net "P1V2_AUX")
		)
		(pad "4" smd rect
			(at -1.550162 0.500126 270)
			(size 0.2794 0.9144)
			(layers "F.Cu" "F.Mask" "F.Paste")
			(net "P1V2_AUX_ADJ")
		)
		(pad "5" smd rect
			(at -1.550162 0.999998 90)
			(size 0.2794 0.9144)
			(layers "F.Cu" "F.Mask" "F.Paste")
			(net "PWRGD_P1V2_AUX")
		)
		(pad "6" smd rect
			(at 1.550162 0.999998 90)
			(size 0.2794 0.9144)
			(layers "F.Cu" "F.Mask" "F.Paste")
			(net "PWR_EN_P1V2_AUX_R")
		)
		(pad "7" smd rect
			(at 1.550162 0.500126 270)
			(size 0.2794 0.9144)
			(layers "F.Cu" "F.Mask" "F.Paste")
			(net "P3V3_AUX")
		)
		(pad "8" smd rect
			(at 1.550162 0 270)
			(size 0.2794 0.9144)
			(layers "F.Cu" "F.Mask" "F.Paste")
			(net "P3V3_AUX")
		)
		(pad "9" smd rect
			(at 1.550162 -0.500126 270)
			(size 0.2794 0.9144)
			(layers "F.Cu" "F.Mask" "F.Paste")
			(net "P3V3_AUX")
		)
		(pad "10" smd rect
			(at 1.550162 -0.999998 270)
			(size 0.2794 0.9144)
			(layers "F.Cu" "F.Mask" "F.Paste")
			(net "P5V_AUX")
		)
		(pad "TH" smd rect
			(at 0 0)
			(size 1.7526 2.667)
			(layers "F.Cu" "F.Mask" "F.Paste")
			(net "GND")
		)
	)
	(footprint ""
		(layer "F.Cu")
		(at 338.492592 -7.742682)
		(property "Reference" "R1714"
			(at 0 0 0)
			(layer "F.SilkS")
			(hide yes)
			(effects
				(font
					(size 1.27 1.27)
				)
			)
		)
		(property "Value" ""
			(at 0 0 0)
			(layer "F.Fab")
			(effects
				(font
					(size 1.27 1.27)
				)
			)
		)
		(duplicate_pad_numbers_are_jumpers no)
		(fp_line
			(start -0.7874 -0.4064)
			(end 0.7874 -0.4064)
			(stroke
				(width 0.1524)
				(type default)
			)
			(layer "F.SilkS")
		)
		(fp_line
			(start -0.7874 0.4064)
			(end -0.7874 -0.4064)
			(stroke
				(width 0.1524)
				(type default)
			)
			(layer "F.SilkS")
		)
		(fp_line
			(start 0.7874 -0.4064)
			(end 0.7874 0.4064)
			(stroke
				(width 0.1524)
				(type default)
			)
			(layer "F.SilkS")
		)
		(fp_line
			(start 0.7874 0.4064)
			(end -0.7874 0.4064)
			(stroke
				(width 0.1524)
				(type default)
			)
			(layer "F.SilkS")
		)
		(fp_line
			(start -0.67945 -0.305054)
			(end -0.12065 -0.305054)
			(stroke
				(width 0.1)
				(type default)
			)
			(layer "F.Fab")
		)
		(fp_line
			(start -0.67945 0.3048)
			(end -0.67945 -0.305054)
			(stroke
				(width 0.1)
				(type default)
			)
			(layer "F.Fab")
		)
		(fp_line
			(start -0.12065 -0.305054)
			(end -0.12065 -0.2794)
			(stroke
				(width 0.1)
				(type default)
			)
			(layer "F.Fab")
		)
		(fp_line
			(start -0.12065 -0.2794)
			(end 0.12065 -0.2794)
			(stroke
				(width 0.1)
				(type default)
			)
			(layer "F.Fab")
		)
		(fp_line
			(start -0.12065 0.2794)
			(end -0.12065 0.3048)
			(stroke
				(width 0.1)
				(type default)
			)
			(layer "F.Fab")
		)
		(fp_line
			(start -0.12065 0.3048)
			(end -0.67945 0.3048)
			(stroke
				(width 0.1)
				(type default)
			)
			(layer "F.Fab")
		)
		(fp_line
			(start 0.120396 0.2794)
			(end -0.12065 0.2794)
			(stroke
				(width 0.1)
				(type default)
			)
			(layer "F.Fab")
		)
		(fp_line
			(start 0.120396 0.3048)
			(end 0.120396 0.2794)
			(stroke
				(width 0.1)
				(type default)
			)
			(layer "F.Fab")
		)
		(fp_line
			(start 0.12065 -0.3048)
			(end 0.67945 -0.3048)
			(stroke
				(width 0.1)
				(type default)
			)
			(layer "F.Fab")
		)
		(fp_line
			(start 0.12065 -0.2794)
			(end 0.12065 -0.3048)
			(stroke
				(width 0.1)
				(type default)
			)
			(layer "F.Fab")
		)
		(fp_line
			(start 0.67945 -0.3048)
			(end 0.67945 0.3048)
			(stroke
				(width 0.1)
				(type default)
			)
			(layer "F.Fab")
		)
		(fp_line
			(start 0.67945 0.3048)
			(end 0.120396 0.3048)
			(stroke
				(width 0.1)
				(type default)
			)
			(layer "F.Fab")
		)
		(pad "1" smd circle
			(at -0.40005 0)
			(size 0 0)
			(layers "F.Cu" "F.Mask" "F.Paste")
			(net "SMB_BIC_I2C9_MUX1_SSD11_R_SCL")
		)
		(pad "2" smd circle
			(at 0.40005 0)
			(size 0 0)
			(layers "F.Cu" "F.Mask" "F.Paste")
			(net "SMB_ISO_SSD11_SCL")
		)
	)
	(footprint ""
		(layer "F.Cu")
		(at 284.443678 -48.93691 180)
		(property "Reference" "R611"
			(at 0 0 180)
			(layer "F.SilkS")
			(hide yes)
			(effects
				(font
					(size 1.27 1.27)
				)
			)
		)
		(property "Value" ""
			(at 0 0 180)
			(layer "F.Fab")
			(effects
				(font
					(size 1.27 1.27)
				)
			)
		)
		(duplicate_pad_numbers_are_jumpers no)
		(fp_line
			(start 0.7874 0.4064)
			(end -0.7874 0.4064)
			(stroke
				(width 0.1524)
				(type default)
			)
			(layer "F.SilkS")
		)
		(fp_line
			(start 0.7874 -0.4064)
			(end 0.7874 0.4064)
			(stroke
				(width 0.1524)
				(type default)
			)
			(layer "F.SilkS")
		)
		(fp_line
			(start -0.7874 0.4064)
			(end -0.7874 -0.4064)
			(stroke
				(width 0.1524)
				(type default)
			)
			(layer "F.SilkS")
		)
		(fp_line
			(start -0.7874 -0.4064)
			(end 0.7874 -0.4064)
			(stroke
				(width 0.1524)
				(type default)
			)
			(layer "F.SilkS")
		)
		(fp_line
			(start 0.67945 0.3048)
			(end 0.120396 0.3048)
			(stroke
				(width 0.1)
				(type default)
			)
			(layer "F.Fab")
		)
		(fp_line
			(start 0.67945 -0.3048)
			(end 0.67945 0.3048)
			(stroke
				(width 0.1)
				(type default)
			)
			(layer "F.Fab")
		)
		(fp_line
			(start 0.12065 -0.2794)
			(end 0.12065 -0.3048)
			(stroke
				(width 0.1)
				(type default)
			)
			(layer "F.Fab")
		)
		(fp_line
			(start 0.12065 -0.3048)
			(end 0.67945 -0.3048)
			(stroke
				(width 0.1)
				(type default)
			)
			(layer "F.Fab")
		)
		(fp_line
			(start 0.120396 0.3048)
			(end 0.120396 0.2794)
			(stroke
				(width 0.1)
				(type default)
			)
			(layer "F.Fab")
		)
		(fp_line
			(start 0.120396 0.2794)
			(end -0.12065 0.2794)
			(stroke
				(width 0.1)
				(type default)
			)
			(layer "F.Fab")
		)
		(fp_line
			(start -0.12065 0.3048)
			(end -0.67945 0.3048)
			(stroke
				(width 0.1)
				(type default)
			)
			(layer "F.Fab")
		)
		(fp_line
			(start -0.12065 0.2794)
			(end -0.12065 0.3048)
			(stroke
				(width 0.1)
				(type default)
			)
			(layer "F.Fab")
		)
		(fp_line
			(start -0.12065 -0.2794)
			(end 0.12065 -0.2794)
			(stroke
				(width 0.1)
				(type default)
			)
			(layer "F.Fab")
		)
		(fp_line
			(start -0.12065 -0.305054)
			(end -0.12065 -0.2794)
			(stroke
				(width 0.1)
				(type default)
			)
			(layer "F.Fab")
		)
		(fp_line
			(start -0.67945 0.3048)
			(end -0.67945 -0.305054)
			(stroke
				(width 0.1)
				(type default)
			)
			(layer "F.Fab")
		)
		(fp_line
			(start -0.67945 -0.305054)
			(end -0.12065 -0.305054)
			(stroke
				(width 0.1)
				(type default)
			)
			(layer "F.Fab")
		)
		(pad "1" smd circle
			(at -0.40005 0 180)
			(size 0 0)
			(layers "F.Cu" "F.Mask" "F.Paste")
			(net "SMB_BIC_I2C6_MUX_SSD_8_15_ADC_R_SDA")
		)
		(pad "2" smd circle
			(at 0.40005 0 180)
			(size 0 0)
			(layers "F.Cu" "F.Mask" "F.Paste")
			(net "SMB_SSD9_ADC_SDA")
		)
	)
	(footprint ""
		(layer "F.Cu")
		(at 260.249162 -284.195012 -90)
		(property "Reference" "C3384"
			(at 0 0 270)
			(layer "F.SilkS")
			(hide yes)
			(effects
				(font
					(size 1.27 1.27)
				)
			)
		)
		(property "Value" ""
			(at 0 0 270)
			(layer "F.Fab")
			(effects
				(font
					(size 1.27 1.27)
				)
			)
		)
		(duplicate_pad_numbers_are_jumpers no)
		(fp_line
			(start -0.299974 0.150114)
			(end -0.299974 -0.150114)
			(stroke
				(width 0.1)
				(type default)
			)
			(layer "F.Fab")
		)
		(fp_line
			(start 0.299974 0.150114)
			(end -0.299974 0.150114)
			(stroke
				(width 0.1)
				(type default)
			)
			(layer "F.Fab")
		)
		(fp_line
			(start -0.299974 -0.150114)
			(end 0.299974 -0.150114)
			(stroke
				(width 0.1)
				(type default)
			)
			(layer "F.Fab")
		)
		(fp_line
			(start 0.299974 -0.150114)
			(end 0.299974 0.150114)
			(stroke
				(width 0.1)
				(type default)
			)
			(layer "F.Fab")
		)
		(pad "1" smd rect
			(at -0.2667 0 270)
			(size 0.3048 0.381)
			(layers "F.Cu" "F.Mask" "F.Paste")
			(net "P1V8_PLL0_PEX2")
		)
		(pad "2" smd rect
			(at 0.2667 0 270)
			(size 0.3048 0.381)
			(layers "F.Cu" "F.Mask" "F.Paste")
			(net "GND")
		)
	)
	(footprint ""
		(layer "F.Cu")
		(at 350.774 -205.232 90)
		(property "Reference" "R4153"
			(at 0 0 90)
			(layer "F.SilkS")
			(hide yes)
			(effects
				(font
					(size 1.27 1.27)
				)
			)
		)
		(property "Value" ""
			(at 0 0 90)
			(layer "F.Fab")
			(effects
				(font
					(size 1.27 1.27)
				)
			)
		)
		(duplicate_pad_numbers_are_jumpers no)
		(fp_line
			(start 0.7874 -0.4064)
			(end 0.7874 0.4064)
			(stroke
				(width 0.1524)
				(type default)
			)
			(layer "F.SilkS")
		)
		(fp_line
			(start -0.7874 -0.4064)
			(end 0.7874 -0.4064)
			(stroke
				(width 0.1524)
				(type default)
			)
			(layer "F.SilkS")
		)
		(fp_line
			(start 0.7874 0.4064)
			(end -0.7874 0.4064)
			(stroke
				(width 0.1524)
				(type default)
			)
			(layer "F.SilkS")
		)
		(fp_line
			(start -0.7874 0.4064)
			(end -0.7874 -0.4064)
			(stroke
				(width 0.1524)
				(type default)
			)
			(layer "F.SilkS")
		)
		(fp_line
			(start -0.12065 -0.305054)
			(end -0.12065 -0.2794)
			(stroke
				(width 0.1)
				(type default)
			)
			(layer "F.Fab")
		)
		(fp_line
			(start -0.67945 -0.305054)
			(end -0.12065 -0.305054)
			(stroke
				(width 0.1)
				(type default)
			)
			(layer "F.Fab")
		)
		(fp_line
			(start 0.67945 -0.3048)
			(end 0.67945 0.3048)
			(stroke
				(width 0.1)
				(type default)
			)
			(layer "F.Fab")
		)
		(fp_line
			(start 0.12065 -0.3048)
			(end 0.67945 -0.3048)
			(stroke
				(width 0.1)
				(type default)
			)
			(layer "F.Fab")
		)
		(fp_line
			(start 0.12065 -0.2794)
			(end 0.12065 -0.3048)
			(stroke
				(width 0.1)
				(type default)
			)
			(layer "F.Fab")
		)
		(fp_line
			(start -0.12065 -0.2794)
			(end 0.12065 -0.2794)
			(stroke
				(width 0.1)
				(type default)
			)
			(layer "F.Fab")
		)
		(fp_line
			(start 0.120396 0.2794)
			(end -0.12065 0.2794)
			(stroke
				(width 0.1)
				(type default)
			)
			(layer "F.Fab")
		)
		(fp_line
			(start -0.12065 0.2794)
			(end -0.12065 0.3048)
			(stroke
				(width 0.1)
				(type default)
			)
			(layer "F.Fab")
		)
		(fp_line
			(start 0.67945 0.3048)
			(end 0.120396 0.3048)
			(stroke
				(width 0.1)
				(type default)
			)
			(layer "F.Fab")
		)
		(fp_line
			(start 0.120396 0.3048)
			(end 0.120396 0.2794)
			(stroke
				(width 0.1)
				(type default)
			)
			(layer "F.Fab")
		)
		(fp_line
			(start -0.12065 0.3048)
			(end -0.67945 0.3048)
			(stroke
				(width 0.1)
				(type default)
			)
			(layer "F.Fab")
		)
		(fp_line
			(start -0.67945 0.3048)
			(end -0.67945 -0.305054)
			(stroke
				(width 0.1)
				(type default)
			)
			(layer "F.Fab")
		)
		(pad "1" smd circle
			(at -0.40005 0 90)
			(size 0 0)
			(layers "F.Cu" "F.Mask" "F.Paste")
			(net "PRSNT_SSD6_FPGA_R_N")
		)
		(pad "2" smd circle
			(at 0.40005 0 90)
			(size 0 0)
			(layers "F.Cu" "F.Mask" "F.Paste")
			(net "PRSNT_SSD6_FPGA_N")
		)
	)
)
